(kicad_pcb
	(version 20260206)
	(generator "pcbnew")
	(generator_version "10.0")
	(general
		(thickness 1.6)
		(legacy_teardrops no)
	)
	(paper "A4")
	(title_block
		(title "04192023_DAF0TMB3IC0_F0TG_MB_C_brd_V02_OCP.brd")
		(comment 1 "Grand Teton / footprints 8127-8134 of 8354")
	)
	(layers
		(0 "F.Cu" signal "TOP")
		(4 "In1.Cu" signal "GND")
		(6 "In2.Cu" signal "IN1")
		(8 "In3.Cu" signal "GND1")
		(10 "In4.Cu" signal "IN2")
		(12 "In5.Cu" signal "GND2")
		(14 "In6.Cu" signal "IN3")
		(16 "In7.Cu" signal "GND3")
		(18 "In8.Cu" signal "VCC")
		(20 "In9.Cu" signal "VCC1")
		(22 "In10.Cu" signal "GND4")
		(24 "In11.Cu" signal "IN4")
		(26 "In12.Cu" signal "GND5")
		(28 "In13.Cu" signal "IN5")
		(30 "In14.Cu" signal "GND6")
		(32 "In15.Cu" signal "IN6")
		(34 "In16.Cu" signal "GND7")
		(2 "B.Cu" signal "BOTTOM")
		(9 "F.Adhes" user "F.Adhesive")
		(11 "B.Adhes" user "B.Adhesive")
		(13 "F.Paste" user "Package Geometry/Pastemask Top")
		(15 "B.Paste" user "Package Geometry/Pastemask Bottom")
		(5 "F.SilkS" user "Ref Des/Silkscreen Top")
		(7 "B.SilkS" user "Ref Des/Silkscreen Bottom")
		(1 "F.Mask" user "Board Geometry/Soldermask Top")
		(3 "B.Mask" user "Board Geometry/Soldermask Bottom")
		(17 "Dwgs.User" user "User.Drawings")
		(19 "Cmts.User" user "User.Comments")
		(21 "Eco1.User" user "User.Eco1")
		(23 "Eco2.User" user "User.Eco2")
		(25 "Edge.Cuts" user "Board Geometry/Outline")
		(27 "Margin" user)
		(31 "F.CrtYd" user "Package Geometry/Place Bound Top")
		(29 "B.CrtYd" user "Package Geometry/Place Bound Bottom")
		(35 "F.Fab" user "Ref Des/Assembly Top")
		(33 "B.Fab" user "Ref Des/Assembly Bottom")
	)
	(footprint ""
		(layer "B.Cu")
		(at 187.890404 -428.965106)
		(property "Reference" "C8016"
			(at 0 0 0)
			(layer "B.SilkS")
			(hide yes)
			(effects
				(font
					(size 1.27 1.27)
				)
				(justify mirror)
			)
		)
		(property "Value" ""
			(at 0 0 0)
			(layer "B.Fab")
			(effects
				(font
					(size 1.27 1.27)
				)
				(justify mirror)
			)
		)
		(duplicate_pad_numbers_are_jumpers no)
		(fp_line
			(start -0.7874 -0.4064)
			(end -0.7874 0.4064)
			(stroke
				(width 0.1524)
				(type default)
			)
			(layer "B.SilkS")
		)
		(fp_line
			(start -0.7874 0.4064)
			(end 0.7874 0.4064)
			(stroke
				(width 0.1524)
				(type default)
			)
			(layer "B.SilkS")
		)
		(fp_line
			(start 0.7874 -0.4064)
			(end -0.7874 -0.4064)
			(stroke
				(width 0.1524)
				(type default)
			)
			(layer "B.SilkS")
		)
		(fp_line
			(start 0.7874 0.4064)
			(end 0.7874 -0.4064)
			(stroke
				(width 0.1524)
				(type default)
			)
			(layer "B.SilkS")
		)
		(fp_line
			(start -0.67945 -0.3048)
			(end -0.67945 0.3048)
			(stroke
				(width 0.1)
				(type default)
			)
			(layer "B.Fab")
		)
		(fp_line
			(start -0.67945 0.3048)
			(end -0.120396 0.3048)
			(stroke
				(width 0.1)
				(type default)
			)
			(layer "B.Fab")
		)
		(fp_line
			(start -0.12065 -0.3048)
			(end -0.67945 -0.3048)
			(stroke
				(width 0.1)
				(type default)
			)
			(layer "B.Fab")
		)
		(fp_line
			(start -0.12065 -0.2794)
			(end -0.12065 -0.3048)
			(stroke
				(width 0.1)
				(type default)
			)
			(layer "B.Fab")
		)
		(fp_line
			(start -0.120396 0.2794)
			(end 0.12065 0.2794)
			(stroke
				(width 0.1)
				(type default)
			)
			(layer "B.Fab")
		)
		(fp_line
			(start -0.120396 0.3048)
			(end -0.120396 0.2794)
			(stroke
				(width 0.1)
				(type default)
			)
			(layer "B.Fab")
		)
		(fp_line
			(start 0.12065 -0.305054)
			(end 0.12065 -0.2794)
			(stroke
				(width 0.1)
				(type default)
			)
			(layer "B.Fab")
		)
		(fp_line
			(start 0.12065 -0.2794)
			(end -0.12065 -0.2794)
			(stroke
				(width 0.1)
				(type default)
			)
			(layer "B.Fab")
		)
		(fp_line
			(start 0.12065 0.2794)
			(end 0.12065 0.3048)
			(stroke
				(width 0.1)
				(type default)
			)
			(layer "B.Fab")
		)
		(fp_line
			(start 0.12065 0.3048)
			(end 0.67945 0.3048)
			(stroke
				(width 0.1)
				(type default)
			)
			(layer "B.Fab")
		)
		(fp_line
			(start 0.67945 -0.305054)
			(end 0.12065 -0.305054)
			(stroke
				(width 0.1)
				(type default)
			)
			(layer "B.Fab")
		)
		(fp_line
			(start 0.67945 0.3048)
			(end 0.67945 -0.305054)
			(stroke
				(width 0.1)
				(type default)
			)
			(layer "B.Fab")
		)
		(pad "1" smd circle
			(at 0.40005 0 180)
			(size 0 0)
			(layers "B.Cu" "B.Mask" "B.Paste")
			(net "P12V_AUX")
		)
		(pad "2" smd circle
			(at -0.40005 0 180)
			(size 0 0)
			(layers "B.Cu" "B.Mask" "B.Paste")
			(net "GND")
		)
	)
	(footprint ""
		(layer "B.Cu")
		(at 338.308696 -335.041494 90)
		(property "Reference" "PC91_1"
			(at 0 0 90)
			(layer "B.SilkS")
			(hide yes)
			(effects
				(font
					(size 1.27 1.27)
				)
				(justify mirror)
			)
		)
		(property "Value" ""
			(at 0 0 90)
			(layer "B.Fab")
			(effects
				(font
					(size 1.27 1.27)
				)
				(justify mirror)
			)
		)
		(duplicate_pad_numbers_are_jumpers no)
		(fp_line
			(start 1.524 -0.762)
			(end -1.524 -0.762)
			(stroke
				(width 0.1524)
				(type default)
			)
			(layer "B.SilkS")
		)
		(fp_line
			(start -1.524 -0.762)
			(end -1.524 0.762)
			(stroke
				(width 0.1524)
				(type default)
			)
			(layer "B.SilkS")
		)
		(fp_line
			(start 1.524 0.762)
			(end 1.524 -0.762)
			(stroke
				(width 0.1524)
				(type default)
			)
			(layer "B.SilkS")
		)
		(fp_line
			(start -1.524 0.762)
			(end 1.524 0.762)
			(stroke
				(width 0.1524)
				(type default)
			)
			(layer "B.SilkS")
		)
		(fp_line
			(start 1.1049 -0.724916)
			(end 1.1049 0.724916)
			(stroke
				(width 0.1)
				(type default)
			)
			(layer "B.Fab")
		)
		(fp_line
			(start -1.1049 -0.724916)
			(end 1.1049 -0.724916)
			(stroke
				(width 0.1)
				(type default)
			)
			(layer "B.Fab")
		)
		(fp_line
			(start 1.1049 0.724916)
			(end -1.1049 0.724916)
			(stroke
				(width 0.1)
				(type default)
			)
			(layer "B.Fab")
		)
		(fp_line
			(start -1.1049 0.724916)
			(end -1.1049 -0.724916)
			(stroke
				(width 0.1)
				(type default)
			)
			(layer "B.Fab")
		)
		(pad "1" smd rect
			(at 0.889 0 90)
			(size 1.016 1.27)
			(layers "B.Cu" "B.Mask" "B.Paste")
			(net "SW_P12V_AUX_PVDDCR_CPU1_P0_FLT")
		)
		(pad "2" smd rect
			(at -0.889 0 90)
			(size 1.016 1.27)
			(layers "B.Cu" "B.Mask" "B.Paste")
			(net "GND")
		)
	)
	(footprint ""
		(layer "B.Cu")
		(at 419.946328 -396.393162 -90)
		(property "Reference" "C984"
			(at 0 0 90)
			(layer "B.SilkS")
			(hide yes)
			(effects
				(font
					(size 1.27 1.27)
				)
				(justify mirror)
			)
		)
		(property "Value" ""
			(at 0 0 90)
			(layer "B.Fab")
			(effects
				(font
					(size 1.27 1.27)
				)
				(justify mirror)
			)
		)
		(duplicate_pad_numbers_are_jumpers no)
		(fp_line
			(start -0.299974 0.150114)
			(end 0.299974 0.150114)
			(stroke
				(width 0.1)
				(type default)
			)
			(layer "B.Fab")
		)
		(fp_line
			(start 0.299974 0.150114)
			(end 0.299974 -0.150114)
			(stroke
				(width 0.1)
				(type default)
			)
			(layer "B.Fab")
		)
		(fp_line
			(start -0.299974 -0.150114)
			(end -0.299974 0.150114)
			(stroke
				(width 0.1)
				(type default)
			)
			(layer "B.Fab")
		)
		(fp_line
			(start 0.299974 -0.150114)
			(end -0.299974 -0.150114)
			(stroke
				(width 0.1)
				(type default)
			)
			(layer "B.Fab")
		)
		(pad "1" smd rect
			(at 0.2667 0 90)
			(size 0.3048 0.381)
			(layers "B.Cu" "B.Mask" "B.Paste")
			(net "P0V9_CPU0_RT2_2A")
		)
		(pad "2" smd rect
			(at -0.2667 0 90)
			(size 0.3048 0.381)
			(layers "B.Cu" "B.Mask" "B.Paste")
			(net "GND")
		)
	)
	(footprint ""
		(layer "B.Cu")
		(at 376.6566 -191.24676 90)
		(property "Reference" "PC564_3"
			(at 0 0 90)
			(layer "B.SilkS")
			(hide yes)
			(effects
				(font
					(size 1.27 1.27)
				)
				(justify mirror)
			)
		)
		(property "Value" ""
			(at 0 0 90)
			(layer "B.Fab")
			(effects
				(font
					(size 1.27 1.27)
				)
				(justify mirror)
			)
		)
		(duplicate_pad_numbers_are_jumpers no)
		(fp_line
			(start 1.524 -0.762)
			(end -1.524 -0.762)
			(stroke
				(width 0.1524)
				(type default)
			)
			(layer "B.SilkS")
		)
		(fp_line
			(start -1.524 -0.762)
			(end -1.524 0.762)
			(stroke
				(width 0.1524)
				(type default)
			)
			(layer "B.SilkS")
		)
		(fp_line
			(start 1.524 0.762)
			(end 1.524 -0.762)
			(stroke
				(width 0.1524)
				(type default)
			)
			(layer "B.SilkS")
		)
		(fp_line
			(start -1.524 0.762)
			(end 1.524 0.762)
			(stroke
				(width 0.1524)
				(type default)
			)
			(layer "B.SilkS")
		)
		(fp_line
			(start 1.1049 -0.724916)
			(end 1.1049 0.724916)
			(stroke
				(width 0.1)
				(type default)
			)
			(layer "B.Fab")
		)
		(fp_line
			(start -1.1049 -0.724916)
			(end 1.1049 -0.724916)
			(stroke
				(width 0.1)
				(type default)
			)
			(layer "B.Fab")
		)
		(fp_line
			(start 1.1049 0.724916)
			(end -1.1049 0.724916)
			(stroke
				(width 0.1)
				(type default)
			)
			(layer "B.Fab")
		)
		(fp_line
			(start -1.1049 0.724916)
			(end -1.1049 -0.724916)
			(stroke
				(width 0.1)
				(type default)
			)
			(layer "B.Fab")
		)
		(pad "1" smd rect
			(at 0.889 0 90)
			(size 1.016 1.27)
			(layers "B.Cu" "B.Mask" "B.Paste")
			(net "PVDDCR_CPU0_P0")
		)
		(pad "2" smd rect
			(at -0.889 0 90)
			(size 1.016 1.27)
			(layers "B.Cu" "B.Mask" "B.Paste")
			(net "GND")
		)
	)
	(footprint ""
		(layer "B.Cu")
		(at 336.846926 -416.899344 90)
		(property "Reference" "C6553"
			(at 0 0 90)
			(layer "B.SilkS")
			(hide yes)
			(effects
				(font
					(size 1.27 1.27)
				)
				(justify mirror)
			)
		)
		(property "Value" ""
			(at 0 0 90)
			(layer "B.Fab")
			(effects
				(font
					(size 1.27 1.27)
				)
				(justify mirror)
			)
		)
		(duplicate_pad_numbers_are_jumpers no)
		(fp_line
			(start 0.299974 -0.150114)
			(end -0.299974 -0.150114)
			(stroke
				(width 0.1)
				(type default)
			)
			(layer "B.Fab")
		)
		(fp_line
			(start -0.299974 -0.150114)
			(end -0.299974 0.150114)
			(stroke
				(width 0.1)
				(type default)
			)
			(layer "B.Fab")
		)
		(fp_line
			(start 0.299974 0.150114)
			(end 0.299974 -0.150114)
			(stroke
				(width 0.1)
				(type default)
			)
			(layer "B.Fab")
		)
		(fp_line
			(start -0.299974 0.150114)
			(end 0.299974 0.150114)
			(stroke
				(width 0.1)
				(type default)
			)
			(layer "B.Fab")
		)
		(pad "1" smd rect
			(at 0.2667 0 270)
			(size 0.3048 0.381)
			(layers "B.Cu" "B.Mask" "B.Paste")
			(net "P5E_CPU0_P1_TX_BUF_C_DP<10>")
		)
		(pad "2" smd rect
			(at -0.2667 0 270)
			(size 0.3048 0.381)
			(layers "B.Cu" "B.Mask" "B.Paste")
			(net "P5E_CPU0_P1_TX_BUF_DP<10>")
		)
	)
	(footprint ""
		(layer "B.Cu")
		(at 354.406454 -266.00531)
		(property "Reference" "C3932"
			(at 0 0 0)
			(layer "B.SilkS")
			(hide yes)
			(effects
				(font
					(size 1.27 1.27)
				)
				(justify mirror)
			)
		)
		(property "Value" ""
			(at 0 0 0)
			(layer "B.Fab")
			(effects
				(font
					(size 1.27 1.27)
				)
				(justify mirror)
			)
		)
		(duplicate_pad_numbers_are_jumpers no)
		(fp_line
			(start -0.7874 -0.4064)
			(end -0.7874 0.4064)
			(stroke
				(width 0.1524)
				(type default)
			)
			(layer "B.SilkS")
		)
		(fp_line
			(start -0.7874 0.4064)
			(end 0.7874 0.4064)
			(stroke
				(width 0.1524)
				(type default)
			)
			(layer "B.SilkS")
		)
		(fp_line
			(start 0.7874 -0.4064)
			(end -0.7874 -0.4064)
			(stroke
				(width 0.1524)
				(type default)
			)
			(layer "B.SilkS")
		)
		(fp_line
			(start 0.7874 0.4064)
			(end 0.7874 -0.4064)
			(stroke
				(width 0.1524)
				(type default)
			)
			(layer "B.SilkS")
		)
		(fp_line
			(start -0.67945 -0.3048)
			(end -0.67945 0.3048)
			(stroke
				(width 0.1)
				(type default)
			)
			(layer "B.Fab")
		)
		(fp_line
			(start -0.67945 0.3048)
			(end -0.120396 0.3048)
			(stroke
				(width 0.1)
				(type default)
			)
			(layer "B.Fab")
		)
		(fp_line
			(start -0.12065 -0.3048)
			(end -0.67945 -0.3048)
			(stroke
				(width 0.1)
				(type default)
			)
			(layer "B.Fab")
		)
		(fp_line
			(start -0.12065 -0.2794)
			(end -0.12065 -0.3048)
			(stroke
				(width 0.1)
				(type default)
			)
			(layer "B.Fab")
		)
		(fp_line
			(start -0.120396 0.2794)
			(end 0.12065 0.2794)
			(stroke
				(width 0.1)
				(type default)
			)
			(layer "B.Fab")
		)
		(fp_line
			(start -0.120396 0.3048)
			(end -0.120396 0.2794)
			(stroke
				(width 0.1)
				(type default)
			)
			(layer "B.Fab")
		)
		(fp_line
			(start 0.12065 -0.305054)
			(end 0.12065 -0.2794)
			(stroke
				(width 0.1)
				(type default)
			)
			(layer "B.Fab")
		)
		(fp_line
			(start 0.12065 -0.2794)
			(end -0.12065 -0.2794)
			(stroke
				(width 0.1)
				(type default)
			)
			(layer "B.Fab")
		)
		(fp_line
			(start 0.12065 0.2794)
			(end 0.12065 0.3048)
			(stroke
				(width 0.1)
				(type default)
			)
			(layer "B.Fab")
		)
		(fp_line
			(start 0.12065 0.3048)
			(end 0.67945 0.3048)
			(stroke
				(width 0.1)
				(type default)
			)
			(layer "B.Fab")
		)
		(fp_line
			(start 0.67945 -0.305054)
			(end 0.12065 -0.305054)
			(stroke
				(width 0.1)
				(type default)
			)
			(layer "B.Fab")
		)
		(fp_line
			(start 0.67945 0.3048)
			(end 0.67945 -0.305054)
			(stroke
				(width 0.1)
				(type default)
			)
			(layer "B.Fab")
		)
		(pad "1" smd circle
			(at 0.40005 0 180)
			(size 0 0)
			(layers "B.Cu" "B.Mask" "B.Paste")
			(net "PVDD11_S3_P0")
		)
		(pad "2" smd circle
			(at -0.40005 0 180)
			(size 0 0)
			(layers "B.Cu" "B.Mask" "B.Paste")
			(net "GND")
		)
	)
	(footprint ""
		(layer "B.Cu")
		(at 239.724692 -422.849548 -90)
		(property "Reference" "R2905"
			(at 0 0 90)
			(layer "B.SilkS")
			(hide yes)
			(effects
				(font
					(size 1.27 1.27)
				)
				(justify mirror)
			)
		)
		(property "Value" ""
			(at 0 0 90)
			(layer "B.Fab")
			(effects
				(font
					(size 1.27 1.27)
				)
				(justify mirror)
			)
		)
		(duplicate_pad_numbers_are_jumpers no)
		(fp_line
			(start -0.7874 0.4064)
			(end 0.7874 0.4064)
			(stroke
				(width 0.1524)
				(type default)
			)
			(layer "B.SilkS")
		)
		(fp_line
			(start 0.7874 0.4064)
			(end 0.7874 -0.4064)
			(stroke
				(width 0.1524)
				(type default)
			)
			(layer "B.SilkS")
		)
		(fp_line
			(start -0.7874 -0.4064)
			(end -0.7874 0.4064)
			(stroke
				(width 0.1524)
				(type default)
			)
			(layer "B.SilkS")
		)
		(fp_line
			(start 0.7874 -0.4064)
			(end -0.7874 -0.4064)
			(stroke
				(width 0.1524)
				(type default)
			)
			(layer "B.SilkS")
		)
		(fp_line
			(start -0.67945 0.3048)
			(end -0.120396 0.3048)
			(stroke
				(width 0.1)
				(type default)
			)
			(layer "B.Fab")
		)
		(fp_line
			(start -0.120396 0.3048)
			(end -0.120396 0.2794)
			(stroke
				(width 0.1)
				(type default)
			)
			(layer "B.Fab")
		)
		(fp_line
			(start 0.12065 0.3048)
			(end 0.67945 0.3048)
			(stroke
				(width 0.1)
				(type default)
			)
			(layer "B.Fab")
		)
		(fp_line
			(start 0.67945 0.3048)
			(end 0.67945 -0.305054)
			(stroke
				(width 0.1)
				(type default)
			)
			(layer "B.Fab")
		)
		(fp_line
			(start -0.120396 0.2794)
			(end 0.12065 0.2794)
			(stroke
				(width 0.1)
				(type default)
			)
			(layer "B.Fab")
		)
		(fp_line
			(start 0.12065 0.2794)
			(end 0.12065 0.3048)
			(stroke
				(width 0.1)
				(type default)
			)
			(layer "B.Fab")
		)
		(fp_line
			(start -0.12065 -0.2794)
			(end -0.12065 -0.3048)
			(stroke
				(width 0.1)
				(type default)
			)
			(layer "B.Fab")
		)
		(fp_line
			(start 0.12065 -0.2794)
			(end -0.12065 -0.2794)
			(stroke
				(width 0.1)
				(type default)
			)
			(layer "B.Fab")
		)
		(fp_line
			(start -0.67945 -0.3048)
			(end -0.67945 0.3048)
			(stroke
				(width 0.1)
				(type default)
			)
			(layer "B.Fab")
		)
		(fp_line
			(start -0.12065 -0.3048)
			(end -0.67945 -0.3048)
			(stroke
				(width 0.1)
				(type default)
			)
			(layer "B.Fab")
		)
		(fp_line
			(start 0.12065 -0.305054)
			(end 0.12065 -0.2794)
			(stroke
				(width 0.1)
				(type default)
			)
			(layer "B.Fab")
		)
		(fp_line
			(start 0.67945 -0.305054)
			(end 0.12065 -0.305054)
			(stroke
				(width 0.1)
				(type default)
			)
			(layer "B.Fab")
		)
		(pad "1" smd circle
			(at 0.40005 0 90)
			(size 0 0)
			(layers "B.Cu" "B.Mask" "B.Paste")
			(net "RST_SMB_SWITCH_N")
		)
		(pad "2" smd circle
			(at -0.40005 0 90)
			(size 0 0)
			(layers "B.Cu" "B.Mask" "B.Paste")
			(net "RST_SMB_SWITCH_R_N")
		)
	)
	(footprint ""
		(layer "B.Cu")
		(at 83.910424 -408.517344 90)
		(property "Reference" "C6683"
			(at 0 0 90)
			(layer "B.SilkS")
			(hide yes)
			(effects
				(font
					(size 1.27 1.27)
				)
				(justify mirror)
			)
		)
		(property "Value" ""
			(at 0 0 90)
			(layer "B.Fab")
			(effects
				(font
					(size 1.27 1.27)
				)
				(justify mirror)
			)
		)
		(duplicate_pad_numbers_are_jumpers no)
		(fp_line
			(start 0.299974 -0.150114)
			(end -0.299974 -0.150114)
			(stroke
				(width 0.1)
				(type default)
			)
			(layer "B.Fab")
		)
		(fp_line
			(start -0.299974 -0.150114)
			(end -0.299974 0.150114)
			(stroke
				(width 0.1)
				(type default)
			)
			(layer "B.Fab")
		)
		(fp_line
			(start 0.299974 0.150114)
			(end 0.299974 -0.150114)
			(stroke
				(width 0.1)
				(type default)
			)
			(layer "B.Fab")
		)
		(fp_line
			(start -0.299974 0.150114)
			(end 0.299974 0.150114)
			(stroke
				(width 0.1)
				(type default)
			)
			(layer "B.Fab")
		)
		(pad "1" smd rect
			(at 0.2667 0 270)
			(size 0.3048 0.381)
			(layers "B.Cu" "B.Mask" "B.Paste")
			(net "P5E_CPU1_P1_TX_BUF_C_DP<11>")
		)
		(pad "2" smd rect
			(at -0.2667 0 270)
			(size 0.3048 0.381)
			(layers "B.Cu" "B.Mask" "B.Paste")
			(net "P5E_CPU1_P1_TX_BUF_DP<11>")
		)
	)
)
